(kicad_pcb
	(version 20260206)
	(generator "pcbnew")
	(generator_version "10.0")
	(general
		(thickness 1.6)
		(legacy_teardrops no)
	)
	(paper "A4")
	(title_block
		(title "Bryce Canyon_IOM_IOC_16318-2_OCP.brd")
		(comment 1 "Bryce Canyon / footprints 874-880 of 1605")
	)
	(layers
		(0 "F.Cu" signal "TOP")
		(4 "In1.Cu" signal "L2GND")
		(6 "In2.Cu" signal "L3")
		(8 "In3.Cu" signal "L4VCC")
		(10 "In4.Cu" signal "L5VCC")
		(12 "In5.Cu" signal "L6")
		(14 "In6.Cu" signal "L7GND")
		(2 "B.Cu" signal "BOTTOM")
		(9 "F.Adhes" user "F.Adhesive")
		(11 "B.Adhes" user "B.Adhesive")
		(13 "F.Paste" user "Package Geometry/Pastemask Top")
		(15 "B.Paste" user "Package Geometry/Pastemask Bottom")
		(5 "F.SilkS" user "Ref Des/Silkscreen Top")
		(7 "B.SilkS" user "Ref Des/Silkscreen Bottom")
		(1 "F.Mask" user "Board Geometry/Soldermask Top")
		(3 "B.Mask" user "Board Geometry/Soldermask Bottom")
		(17 "Dwgs.User" user "User.Drawings")
		(19 "Cmts.User" user "User.Comments")
		(21 "Eco1.User" user "User.Eco1")
		(23 "Eco2.User" user "User.Eco2")
		(25 "Edge.Cuts" user "Board Geometry/Outline")
		(27 "Margin" user)
		(31 "F.CrtYd" user "Package Geometry/Place Bound Top")
		(29 "B.CrtYd" user "Package Geometry/Place Bound Bottom")
		(35 "F.Fab" user "Ref Des/Assembly Top")
		(33 "B.Fab" user "Ref Des/Assembly Bottom")
	)
	(footprint ""
		(layer "F.Cu")
		(at 199.893936 -128.4224 90)
		(property "Reference" "R548"
			(at 0 0 90)
			(layer "F.SilkS")
			(hide yes)
			(effects
				(font
					(size 1.27 1.27)
				)
			)
		)
		(property "Value" "4K75R2F-1-GP"
			(at 0.064008 -3.993896 90)
			(unlocked yes)
			(layer "F.Fab")
			(hide yes)
			(effects
				(font
					(size 1.016 1.016)
					(thickness 0.1524)
				)
			)
		)
		(property "Device Type" "R402H16"
			(at 0.064008 -5.517896 90)
			(unlocked yes)
			(layer "F.Fab")
			(hide yes)
			(effects
				(font
					(size 1.016 1.016)
					(thickness 0.1524)
				)
			)
		)
		(duplicate_pad_numbers_are_jumpers no)
		(fp_line
			(start 0.508 -0.9398)
			(end -0.508 -0.9398)
			(stroke
				(width 0.1524)
				(type default)
			)
			(layer "F.SilkS")
		)
		(fp_line
			(start -0.508 -0.9398)
			(end -0.508 0.9398)
			(stroke
				(width 0.1524)
				(type default)
			)
			(layer "F.SilkS")
		)
		(fp_rect
			(start -0.508 0.9398)
			(end 0.508 -0.9398)
			(stroke
				(width 0)
				(type default)
			)
			(fill no)
			(layer "F.CrtYd")
		)
		(fp_rect
			(start -0.508 0.9398)
			(end 0.508 -0.9398)
			(stroke
				(width 0)
				(type default)
			)
			(fill no)
			(layer "F.Fab")
		)
		(pad "1" smd custom
			(at 0 -0.4445 90)
			(size 0.1397 0.1397)
			(layers "F.Cu" "F.Mask" "F.Paste")
			(net "P3V3_STBY")
			(options
				(clearance outline)
				(anchor circle)
			)
			(primitives
				(gr_poly
					(pts
						(arc
							(start -0.1778 -0.2794)
							(mid -0.249642 -0.249642)
							(end -0.2794 -0.1778)
						)
						(arc
							(start -0.2794 0.1778)
							(mid -0.249642 0.249642)
							(end -0.1778 0.2794)
						)
						(arc
							(start 0.1778 0.2794)
							(mid 0.249642 0.249642)
							(end 0.2794 0.1778)
						)
						(arc
							(start 0.2794 -0.1778)
							(mid 0.249642 -0.249642)
							(end 0.1778 -0.2794)
						)
					)
					(width 0)
					(fill yes)
				)
			)
		)
		(pad "2" smd custom
			(at 0 0.4445 90)
			(size 0.1397 0.1397)
			(layers "F.Cu" "F.Mask" "F.Paste")
			(net "TPS74801_1V5_EN")
			(options
				(clearance outline)
				(anchor circle)
			)
			(primitives
				(gr_poly
					(pts
						(arc
							(start -0.1778 -0.2794)
							(mid -0.249642 -0.249642)
							(end -0.2794 -0.1778)
						)
						(arc
							(start -0.2794 0.1778)
							(mid -0.249642 0.249642)
							(end -0.1778 0.2794)
						)
						(arc
							(start 0.1778 0.2794)
							(mid 0.249642 0.249642)
							(end 0.2794 0.1778)
						)
						(arc
							(start 0.2794 -0.1778)
							(mid 0.249642 -0.249642)
							(end 0.1778 -0.2794)
						)
					)
					(width 0)
					(fill yes)
				)
			)
		)
	)
	(footprint ""
		(layer "F.Cu")
		(at 81.8134 -163.449)
		(property "Reference" "C242"
			(at 0 0 0)
			(layer "F.SilkS")
			(hide yes)
			(effects
				(font
					(size 1.27 1.27)
				)
			)
		)
		(property "Value" "SCD1U16V2KX-3GP"
			(at 1.1811 -2.7051 0)
			(unlocked yes)
			(layer "F.Fab")
			(hide yes)
			(effects
				(font
					(size 1.016 1.016)
					(thickness 0.1524)
				)
			)
		)
		(property "Device Type" "C402H22"
			(at 1.1811 -4.2291 0)
			(unlocked yes)
			(layer "F.Fab")
			(hide yes)
			(effects
				(font
					(size 1.016 1.016)
					(thickness 0.1524)
				)
			)
		)
		(duplicate_pad_numbers_are_jumpers no)
		(fp_rect
			(start -0.4318 0.9525)
			(end 0.4318 -0.9525)
			(stroke
				(width 0)
				(type default)
			)
			(fill no)
			(layer "F.CrtYd")
		)
		(fp_rect
			(start -0.4318 0.9525)
			(end 0.4318 -0.9525)
			(stroke
				(width 0)
				(type default)
			)
			(fill no)
			(layer "F.Fab")
		)
		(pad "1" smd custom
			(at 0 -0.4445)
			(size 0.1524 0.1524)
			(layers "F.Cu" "F.Mask" "F.Paste")
			(net "P1V8_STBY")
			(options
				(clearance outline)
				(anchor circle)
			)
			(primitives
				(gr_poly
					(pts
						(arc
							(start 0.3048 -0.2032)
							(mid 0.275042 -0.275042)
							(end 0.2032 -0.3048)
						)
						(arc
							(start -0.2032 -0.3048)
							(mid -0.275042 -0.275042)
							(end -0.3048 -0.2032)
						)
						(arc
							(start -0.3048 0.2032)
							(mid -0.275042 0.275042)
							(end -0.2032 0.3048)
						)
						(arc
							(start 0.2032 0.3048)
							(mid 0.275042 0.275042)
							(end 0.3048 0.2032)
						)
					)
					(width 0)
					(fill yes)
				)
			)
		)
		(pad "2" smd custom
			(at 0 0.4445)
			(size 0.1524 0.1524)
			(layers "F.Cu" "F.Mask" "F.Paste")
			(net "GND")
			(options
				(clearance outline)
				(anchor circle)
			)
			(primitives
				(gr_poly
					(pts
						(arc
							(start 0.3048 -0.2032)
							(mid 0.275042 -0.275042)
							(end 0.2032 -0.3048)
						)
						(arc
							(start -0.2032 -0.3048)
							(mid -0.275042 -0.275042)
							(end -0.3048 -0.2032)
						)
						(arc
							(start -0.3048 0.2032)
							(mid -0.275042 0.275042)
							(end -0.2032 0.3048)
						)
						(arc
							(start 0.2032 0.3048)
							(mid 0.275042 0.275042)
							(end 0.3048 0.2032)
						)
					)
					(width 0)
					(fill yes)
				)
			)
		)
	)
	(footprint ""
		(layer "F.Cu")
		(at 208.055972 -64.4144 90)
		(property "Reference" "C322"
			(at 0 0 90)
			(layer "F.SilkS")
			(hide yes)
			(effects
				(font
					(size 1.27 1.27)
				)
			)
		)
		(property "Value" "SCD01U16V1KX-GP"
			(at -2.8321 -1.7399 90)
			(unlocked yes)
			(layer "F.Fab")
			(hide yes)
			(effects
				(font
					(size 1.016 1.016)
					(thickness 0.1524)
				)
			)
		)
		(property "Device Type" "C0201H13"
			(at -2.8321 -3.2639 90)
			(unlocked yes)
			(layer "F.Fab")
			(hide yes)
			(effects
				(font
					(size 1.016 1.016)
					(thickness 0.1524)
				)
			)
		)
		(duplicate_pad_numbers_are_jumpers no)
		(fp_rect
			(start -0.2794 0.6477)
			(end 0.2794 -0.6477)
			(stroke
				(width 0)
				(type default)
			)
			(fill no)
			(layer "F.CrtYd")
		)
		(fp_rect
			(start -0.2794 0.6477)
			(end 0.2794 -0.6477)
			(stroke
				(width 0)
				(type default)
			)
			(fill no)
			(layer "F.Fab")
		)
		(pad "1" smd custom
			(at 0 -0.2794 90)
			(size 0.0762 0.0762)
			(layers "F.Cu" "F.Mask" "F.Paste")
			(net "PHY_IOC_TO_CON_B_3_DN_C")
			(options
				(clearance outline)
				(anchor circle)
			)
			(primitives
				(gr_poly
					(pts
						(arc
							(start 0.1524 -0.127)
							(mid 0.137521 -0.162921)
							(end 0.1016 -0.1778)
						)
						(arc
							(start -0.1016 -0.1778)
							(mid -0.137521 -0.162921)
							(end -0.1524 -0.127)
						)
						(arc
							(start -0.1524 0.127)
							(mid -0.137521 0.162921)
							(end -0.1016 0.1778)
						)
						(arc
							(start 0.1016 0.1778)
							(mid 0.137521 0.162921)
							(end 0.1524 0.127)
						)
					)
					(width 0)
					(fill yes)
				)
			)
		)
		(pad "2" smd custom
			(at 0 0.2794 90)
			(size 0.0762 0.0762)
			(layers "F.Cu" "F.Mask" "F.Paste")
			(net "PHY_IOC_TO_CON_B_3_DN")
			(options
				(clearance outline)
				(anchor circle)
			)
			(primitives
				(gr_poly
					(pts
						(arc
							(start 0.1524 -0.127)
							(mid 0.137521 -0.162921)
							(end 0.1016 -0.1778)
						)
						(arc
							(start -0.1016 -0.1778)
							(mid -0.137521 -0.162921)
							(end -0.1524 -0.127)
						)
						(arc
							(start -0.1524 0.127)
							(mid -0.137521 0.162921)
							(end -0.1016 0.1778)
						)
						(arc
							(start 0.1016 0.1778)
							(mid 0.137521 0.162921)
							(end 0.1524 0.127)
						)
					)
					(width 0)
					(fill yes)
				)
			)
		)
	)
	(footprint ""
		(layer "F.Cu")
		(at 190.881 -13.01242 180)
		(property "Reference" "R800"
			(at 0 0 180)
			(layer "F.SilkS")
			(hide yes)
			(effects
				(font
					(size 1.27 1.27)
				)
			)
		)
		(property "Value" "130R3F-GP"
			(at -0.0254 -2.5146 180)
			(unlocked yes)
			(layer "F.Fab")
			(hide yes)
			(effects
				(font
					(size 1.016 1.016)
					(thickness 0.1524)
				)
			)
		)
		(property "Device Type" "R603H22"
			(at -0.0254 -4.0386 180)
			(unlocked yes)
			(layer "F.Fab")
			(hide yes)
			(effects
				(font
					(size 1.016 1.016)
					(thickness 0.1524)
				)
			)
		)
		(duplicate_pad_numbers_are_jumpers no)
		(fp_line
			(start 0.2032 0)
			(end 0.4826 0)
			(stroke
				(width 0.2032)
				(type default)
			)
			(layer "F.SilkS")
		)
		(fp_line
			(start -0.4826 0)
			(end -0.2032 0)
			(stroke
				(width 0.2032)
				(type default)
			)
			(layer "F.SilkS")
		)
		(fp_rect
			(start -0.5842 1.3335)
			(end 0.5842 -1.3335)
			(stroke
				(width 0)
				(type default)
			)
			(fill no)
			(layer "F.CrtYd")
		)
		(fp_rect
			(start -0.5842 1.3335)
			(end 0.5842 -1.3335)
			(stroke
				(width 0)
				(type default)
			)
			(fill no)
			(layer "F.Fab")
		)
		(pad "1" smd custom
			(at 0 -0.762 180)
			(size 0.2159 0.2159)
			(layers "F.Cu" "F.Mask" "F.Paste")
			(net "EXT1_LED_BLUE")
			(options
				(clearance outline)
				(anchor circle)
			)
			(primitives
				(gr_poly
					(pts
						(arc
							(start -0.3302 -0.4318)
							(mid -0.402042 -0.402042)
							(end -0.4318 -0.3302)
						)
						(arc
							(start -0.4318 0.3302)
							(mid -0.402042 0.402042)
							(end -0.3302 0.4318)
						)
						(arc
							(start 0.3302 0.4318)
							(mid 0.402042 0.402042)
							(end 0.4318 0.3302)
						)
						(arc
							(start 0.4318 -0.3302)
							(mid 0.402042 -0.402042)
							(end 0.3302 -0.4318)
						)
					)
					(width 0)
					(fill yes)
				)
			)
		)
		(pad "2" smd custom
			(at 0 0.762 180)
			(size 0.2159 0.2159)
			(layers "F.Cu" "F.Mask" "F.Paste")
			(net "EXT1_LED_BLUE_D")
			(options
				(clearance outline)
				(anchor circle)
			)
			(primitives
				(gr_poly
					(pts
						(arc
							(start -0.3302 -0.4318)
							(mid -0.402042 -0.402042)
							(end -0.4318 -0.3302)
						)
						(arc
							(start -0.4318 0.3302)
							(mid -0.402042 0.402042)
							(end -0.3302 0.4318)
						)
						(arc
							(start 0.3302 0.4318)
							(mid 0.402042 0.402042)
							(end 0.4318 0.3302)
						)
						(arc
							(start 0.4318 -0.3302)
							(mid 0.402042 -0.402042)
							(end 0.3302 -0.4318)
						)
					)
					(width 0)
					(fill yes)
				)
			)
		)
	)
	(footprint ""
		(layer "F.Cu")
		(at 58.7502 -163.5252 180)
		(property "Reference" "R410"
			(at 0 0 180)
			(layer "F.SilkS")
			(hide yes)
			(effects
				(font
					(size 1.27 1.27)
				)
			)
		)
		(property "Value" "1KR2F-3-GP"
			(at 0.064008 -3.993896 180)
			(unlocked yes)
			(layer "F.Fab")
			(hide yes)
			(effects
				(font
					(size 1.016 1.016)
					(thickness 0.1524)
				)
			)
		)
		(property "Device Type" "R402H16"
			(at 0.064008 -5.517896 180)
			(unlocked yes)
			(layer "F.Fab")
			(hide yes)
			(effects
				(font
					(size 1.016 1.016)
					(thickness 0.1524)
				)
			)
		)
		(duplicate_pad_numbers_are_jumpers no)
		(fp_line
			(start 0.508 -0.9398)
			(end -0.508 -0.9398)
			(stroke
				(width 0.1524)
				(type default)
			)
			(layer "F.SilkS")
		)
		(fp_line
			(start -0.508 -0.9398)
			(end -0.508 0.9398)
			(stroke
				(width 0.1524)
				(type default)
			)
			(layer "F.SilkS")
		)
		(fp_rect
			(start -0.508 0.9398)
			(end 0.508 -0.9398)
			(stroke
				(width 0)
				(type default)
			)
			(fill no)
			(layer "F.CrtYd")
		)
		(fp_rect
			(start -0.508 0.9398)
			(end 0.508 -0.9398)
			(stroke
				(width 0)
				(type default)
			)
			(fill no)
			(layer "F.Fab")
		)
		(pad "1" smd custom
			(at 0 -0.4445 180)
			(size 0.1397 0.1397)
			(layers "F.Cu" "F.Mask" "F.Paste")
			(net "ADC_P3V3_STBY")
			(options
				(clearance outline)
				(anchor circle)
			)
			(primitives
				(gr_poly
					(pts
						(arc
							(start -0.1778 -0.2794)
							(mid -0.249642 -0.249642)
							(end -0.2794 -0.1778)
						)
						(arc
							(start -0.2794 0.1778)
							(mid -0.249642 0.249642)
							(end -0.1778 0.2794)
						)
						(arc
							(start 0.1778 0.2794)
							(mid 0.249642 0.249642)
							(end 0.2794 0.1778)
						)
						(arc
							(start 0.2794 -0.1778)
							(mid 0.249642 -0.249642)
							(end 0.1778 -0.2794)
						)
					)
					(width 0)
					(fill yes)
				)
			)
		)
		(pad "2" smd custom
			(at 0 0.4445 180)
			(size 0.1397 0.1397)
			(layers "F.Cu" "F.Mask" "F.Paste")
			(net "GND")
			(options
				(clearance outline)
				(anchor circle)
			)
			(primitives
				(gr_poly
					(pts
						(arc
							(start -0.1778 -0.2794)
							(mid -0.249642 -0.249642)
							(end -0.2794 -0.1778)
						)
						(arc
							(start -0.2794 0.1778)
							(mid -0.249642 0.249642)
							(end -0.1778 0.2794)
						)
						(arc
							(start 0.1778 0.2794)
							(mid 0.249642 0.249642)
							(end 0.2794 0.1778)
						)
						(arc
							(start 0.2794 -0.1778)
							(mid 0.249642 -0.249642)
							(end 0.1778 -0.2794)
						)
					)
					(width 0)
					(fill yes)
				)
			)
		)
	)
	(footprint ""
		(layer "F.Cu")
		(at 57.2516 -181.5592)
		(property "Reference" "C169"
			(at 0 0 0)
			(layer "F.SilkS")
			(hide yes)
			(effects
				(font
					(size 1.27 1.27)
				)
			)
		)
		(property "Value" "SCD1U16V2KX-3GP"
			(at 1.1811 -2.7051 0)
			(unlocked yes)
			(layer "F.Fab")
			(hide yes)
			(effects
				(font
					(size 1.016 1.016)
					(thickness 0.1524)
				)
			)
		)
		(property "Device Type" "C402H22"
			(at 1.1811 -4.2291 0)
			(unlocked yes)
			(layer "F.Fab")
			(hide yes)
			(effects
				(font
					(size 1.016 1.016)
					(thickness 0.1524)
				)
			)
		)
		(duplicate_pad_numbers_are_jumpers no)
		(fp_rect
			(start -0.4318 0.9525)
			(end 0.4318 -0.9525)
			(stroke
				(width 0)
				(type default)
			)
			(fill no)
			(layer "F.CrtYd")
		)
		(fp_rect
			(start -0.4318 0.9525)
			(end 0.4318 -0.9525)
			(stroke
				(width 0)
				(type default)
			)
			(fill no)
			(layer "F.Fab")
		)
		(pad "1" smd custom
			(at 0 -0.4445)
			(size 0.1524 0.1524)
			(layers "F.Cu" "F.Mask" "F.Paste")
			(net "P3V3_STBY_OUT")
			(options
				(clearance outline)
				(anchor circle)
			)
			(primitives
				(gr_poly
					(pts
						(arc
							(start 0.3048 -0.2032)
							(mid 0.275042 -0.275042)
							(end 0.2032 -0.3048)
						)
						(arc
							(start -0.2032 -0.3048)
							(mid -0.275042 -0.275042)
							(end -0.3048 -0.2032)
						)
						(arc
							(start -0.3048 0.2032)
							(mid -0.275042 0.275042)
							(end -0.2032 0.3048)
						)
						(arc
							(start 0.2032 0.3048)
							(mid 0.275042 0.275042)
							(end 0.3048 0.2032)
						)
					)
					(width 0)
					(fill yes)
				)
			)
		)
		(pad "2" smd custom
			(at 0 0.4445)
			(size 0.1524 0.1524)
			(layers "F.Cu" "F.Mask" "F.Paste")
			(net "GND")
			(options
				(clearance outline)
				(anchor circle)
			)
			(primitives
				(gr_poly
					(pts
						(arc
							(start 0.3048 -0.2032)
							(mid 0.275042 -0.275042)
							(end 0.2032 -0.3048)
						)
						(arc
							(start -0.2032 -0.3048)
							(mid -0.275042 -0.275042)
							(end -0.3048 -0.2032)
						)
						(arc
							(start -0.3048 0.2032)
							(mid -0.275042 0.275042)
							(end -0.2032 0.3048)
						)
						(arc
							(start 0.2032 0.3048)
							(mid 0.275042 0.275042)
							(end 0.3048 0.2032)
						)
					)
					(width 0)
					(fill yes)
				)
			)
		)
	)
	(footprint ""
		(layer "F.Cu")
		(at 143.22298 -13.310362 180)
		(property "Reference" "R801"
			(at 0 0 180)
			(layer "F.SilkS")
			(hide yes)
			(effects
				(font
					(size 1.27 1.27)
				)
			)
		)
		(property "Value" "130R3F-GP"
			(at -0.0254 -2.5146 180)
			(unlocked yes)
			(layer "F.Fab")
			(hide yes)
			(effects
				(font
					(size 1.016 1.016)
					(thickness 0.1524)
				)
			)
		)
		(property "Device Type" "R603H22"
			(at -0.0254 -4.0386 180)
			(unlocked yes)
			(layer "F.Fab")
			(hide yes)
			(effects
				(font
					(size 1.016 1.016)
					(thickness 0.1524)
				)
			)
		)
		(duplicate_pad_numbers_are_jumpers no)
		(fp_line
			(start 0.2032 0)
			(end 0.4826 0)
			(stroke
				(width 0.2032)
				(type default)
			)
			(layer "F.SilkS")
		)
		(fp_line
			(start -0.4826 0)
			(end -0.2032 0)
			(stroke
				(width 0.2032)
				(type default)
			)
			(layer "F.SilkS")
		)
		(fp_rect
			(start -0.5842 1.3335)
			(end 0.5842 -1.3335)
			(stroke
				(width 0)
				(type default)
			)
			(fill no)
			(layer "F.CrtYd")
		)
		(fp_rect
			(start -0.5842 1.3335)
			(end 0.5842 -1.3335)
			(stroke
				(width 0)
				(type default)
			)
			(fill no)
			(layer "F.Fab")
		)
		(pad "1" smd custom
			(at 0 -0.762 180)
			(size 0.2159 0.2159)
			(layers "F.Cu" "F.Mask" "F.Paste")
			(net "EXT2_LED_BLUE")
			(options
				(clearance outline)
				(anchor circle)
			)
			(primitives
				(gr_poly
					(pts
						(arc
							(start -0.3302 -0.4318)
							(mid -0.402042 -0.402042)
							(end -0.4318 -0.3302)
						)
						(arc
							(start -0.4318 0.3302)
							(mid -0.402042 0.402042)
							(end -0.3302 0.4318)
						)
						(arc
							(start 0.3302 0.4318)
							(mid 0.402042 0.402042)
							(end 0.4318 0.3302)
						)
						(arc
							(start 0.4318 -0.3302)
							(mid 0.402042 -0.402042)
							(end 0.3302 -0.4318)
						)
					)
					(width 0)
					(fill yes)
				)
			)
		)
		(pad "2" smd custom
			(at 0 0.762 180)
			(size 0.2159 0.2159)
			(layers "F.Cu" "F.Mask" "F.Paste")
			(net "EXT2_LED_BLUE_D")
			(options
				(clearance outline)
				(anchor circle)
			)
			(primitives
				(gr_poly
					(pts
						(arc
							(start -0.3302 -0.4318)
							(mid -0.402042 -0.402042)
							(end -0.4318 -0.3302)
						)
						(arc
							(start -0.4318 0.3302)
							(mid -0.402042 0.402042)
							(end -0.3302 0.4318)
						)
						(arc
							(start 0.3302 0.4318)
							(mid 0.402042 0.402042)
							(end 0.4318 0.3302)
						)
						(arc
							(start 0.4318 -0.3302)
							(mid 0.402042 -0.402042)
							(end 0.3302 -0.4318)
						)
					)
					(width 0)
					(fill yes)
				)
			)
		)
	)
)
